# S9S_MB_2U (Grand Teton) — schematic netlist excerpt (pin names and nets, part order shuffled) for the footprints in the layout excerpt that follows; sources: Cadence DE-HDL packaged netlist, KiCad conversion of 03242023_DA0F0TMBIJ0_F0T_Motherboard_J_brd_V01_OCP.brd

C1396  Q_CAP  47UF 4V 20% X6S  pkg C0805  page 75 : A = PVPP_HBM_CPU0 ; B = GND
C370  Q_CAP  47UF 4V 20% X6S  pkg C0805  page 75 : A = PVCCIN_CPU0 ; B = GND
R2726  Q_RES  33.2 1% CHIP  pkg 0402LF  page 114 : A = PWRGD_CHA_CPU0_DIMM1 ; B = PWRGD_FAIL_CPU0_AB

(kicad_pcb
	(version 20260206)
	(generator "pcbnew")
	(generator_version "10.0")
	(general
		(thickness 1.6)
		(legacy_teardrops no)
	)
	(paper "A4")
	(title_block
		(title "03242023_DA0F0TMBIJ0_F0T_Motherboard_J_brd_V01_OCP.brd")
		(comment 1 "Grand Teton / footprints 4630-4632 of 6105")
	)
	(layers
		(0 "F.Cu" signal "TOP")
		(4 "In1.Cu" signal "GND")
		(6 "In2.Cu" signal "IN1")
		(8 "In3.Cu" signal "GND1")
		(10 "In4.Cu" signal "IN2")
		(12 "In5.Cu" signal "GND2")
		(14 "In6.Cu" signal "IN3")
		(16 "In7.Cu" signal "GND3")
		(18 "In8.Cu" signal "VCC")
		(20 "In9.Cu" signal "VCC1")
		(22 "In10.Cu" signal "GND4")
		(24 "In11.Cu" signal "IN4")
		(26 "In12.Cu" signal "GND5")
		(28 "In13.Cu" signal "IN5")
		(30 "In14.Cu" signal "GND6")
		(32 "In15.Cu" signal "IN6")
		(34 "In16.Cu" signal "GND7")
		(2 "B.Cu" signal "BOTTOM")
		(9 "F.Adhes" user "F.Adhesive")
		(11 "B.Adhes" user "B.Adhesive")
		(13 "F.Paste" user "Package Geometry/Pastemask Top")
		(15 "B.Paste" user "Package Geometry/Pastemask Bottom")
		(5 "F.SilkS" user "Ref Des/Silkscreen Top")
		(7 "B.SilkS" user "Ref Des/Silkscreen Bottom")
		(1 "F.Mask" user "Board Geometry/Soldermask Top")
		(3 "B.Mask" user "Board Geometry/Soldermask Bottom")
		(17 "Dwgs.User" user "User.Drawings")
		(19 "Cmts.User" user "User.Comments")
		(21 "Eco1.User" user "User.Eco1")
		(23 "Eco2.User" user "User.Eco2")
		(25 "Edge.Cuts" user "Board Geometry/Outline")
		(27 "Margin" user)
		(31 "F.CrtYd" user "Package Geometry/Place Bound Top")
		(29 "B.CrtYd" user "Package Geometry/Place Bound Bottom")
		(35 "F.Fab" user "Ref Des/Assembly Top")
		(33 "B.Fab" user "Ref Des/Assembly Bottom")
	)
	(footprint ""
		(layer "B.Cu")
		(at 304.718466 -319.061846 90)
		(property "Reference" "R2726"
			(at 0 0 90)
			(layer "B.SilkS")
			(hide yes)
			(effects
				(font
					(size 1.27 1.27)
				)
				(justify mirror)
			)
		)
		(property "Value" ""
			(at 0 0 90)
			(layer "B.Fab")
			(effects
				(font
					(size 1.27 1.27)
				)
				(justify mirror)
			)
		)
		(duplicate_pad_numbers_are_jumpers no)
		(fp_line
			(start 0.7874 -0.4064)
			(end -0.7874 -0.4064)
			(stroke
				(width 0.1524)
				(type default)
			)
			(layer "B.SilkS")
		)
		(fp_line
			(start -0.7874 -0.4064)
			(end -0.7874 0.4064)
			(stroke
				(width 0.1524)
				(type default)
			)
			(layer "B.SilkS")
		)
		(fp_line
			(start 0.7874 0.4064)
			(end 0.7874 -0.4064)
			(stroke
				(width 0.1524)
				(type default)
			)
			(layer "B.SilkS")
		)
		(fp_line
			(start -0.7874 0.4064)
			(end 0.7874 0.4064)
			(stroke
				(width 0.1524)
				(type default)
			)
			(layer "B.SilkS")
		)
		(fp_line
			(start 0.67945 -0.305054)
			(end 0.12065 -0.305054)
			(stroke
				(width 0.1)
				(type default)
			)
			(layer "B.Fab")
		)
		(fp_line
			(start 0.12065 -0.305054)
			(end 0.12065 -0.2794)
			(stroke
				(width 0.1)
				(type default)
			)
			(layer "B.Fab")
		)
		(fp_line
			(start -0.12065 -0.3048)
			(end -0.67945 -0.3048)
			(stroke
				(width 0.1)
				(type default)
			)
			(layer "B.Fab")
		)
		(fp_line
			(start -0.67945 -0.3048)
			(end -0.67945 0.3048)
			(stroke
				(width 0.1)
				(type default)
			)
			(layer "B.Fab")
		)
		(fp_line
			(start 0.12065 -0.2794)
			(end -0.12065 -0.2794)
			(stroke
				(width 0.1)
				(type default)
			)
			(layer "B.Fab")
		)
		(fp_line
			(start -0.12065 -0.2794)
			(end -0.12065 -0.3048)
			(stroke
				(width 0.1)
				(type default)
			)
			(layer "B.Fab")
		)
		(fp_line
			(start 0.12065 0.2794)
			(end 0.12065 0.3048)
			(stroke
				(width 0.1)
				(type default)
			)
			(layer "B.Fab")
		)
		(fp_line
			(start -0.120396 0.2794)
			(end 0.12065 0.2794)
			(stroke
				(width 0.1)
				(type default)
			)
			(layer "B.Fab")
		)
		(fp_line
			(start 0.67945 0.3048)
			(end 0.67945 -0.305054)
			(stroke
				(width 0.1)
				(type default)
			)
			(layer "B.Fab")
		)
		(fp_line
			(start 0.12065 0.3048)
			(end 0.67945 0.3048)
			(stroke
				(width 0.1)
				(type default)
			)
			(layer "B.Fab")
		)
		(fp_line
			(start -0.120396 0.3048)
			(end -0.120396 0.2794)
			(stroke
				(width 0.1)
				(type default)
			)
			(layer "B.Fab")
		)
		(fp_line
			(start -0.67945 0.3048)
			(end -0.120396 0.3048)
			(stroke
				(width 0.1)
				(type default)
			)
			(layer "B.Fab")
		)
		(pad "1" smd circle
			(at 0.40005 0 270)
			(size 0 0)
			(layers "B.Cu" "B.Mask" "B.Paste")
			(net "PWRGD_CHA_CPU0_DIMM1")
		)
		(pad "2" smd circle
			(at -0.40005 0 270)
			(size 0 0)
			(layers "B.Cu" "B.Mask" "B.Paste")
			(net "PWRGD_FAIL_CPU0_AB")
		)
	)
	(footprint ""
		(layer "B.Cu")
		(at 367.898934 -252.176026 -90)
		(property "Reference" "C370"
			(at 0 0 90)
			(layer "B.SilkS")
			(hide yes)
			(effects
				(font
					(size 1.27 1.27)
				)
				(justify mirror)
			)
		)
		(property "Value" ""
			(at 0 0 90)
			(layer "B.Fab")
			(effects
				(font
					(size 1.27 1.27)
				)
				(justify mirror)
			)
		)
		(duplicate_pad_numbers_are_jumpers no)
		(fp_line
			(start -1.524 0.762)
			(end 1.524 0.762)
			(stroke
				(width 0.1524)
				(type default)
			)
			(layer "B.SilkS")
		)
		(fp_line
			(start 1.524 0.762)
			(end 1.524 -0.762)
			(stroke
				(width 0.1524)
				(type default)
			)
			(layer "B.SilkS")
		)
		(fp_line
			(start -1.524 -0.762)
			(end -1.524 0.762)
			(stroke
				(width 0.1524)
				(type default)
			)
			(layer "B.SilkS")
		)
		(fp_line
			(start 1.524 -0.762)
			(end -1.524 -0.762)
			(stroke
				(width 0.1524)
				(type default)
			)
			(layer "B.SilkS")
		)
		(fp_line
			(start -1.1049 0.724916)
			(end -1.1049 -0.724916)
			(stroke
				(width 0.1)
				(type default)
			)
			(layer "B.Fab")
		)
		(fp_line
			(start 1.1049 0.724916)
			(end -1.1049 0.724916)
			(stroke
				(width 0.1)
				(type default)
			)
			(layer "B.Fab")
		)
		(fp_line
			(start -1.1049 -0.724916)
			(end 1.1049 -0.724916)
			(stroke
				(width 0.1)
				(type default)
			)
			(layer "B.Fab")
		)
		(fp_line
			(start 1.1049 -0.724916)
			(end 1.1049 0.724916)
			(stroke
				(width 0.1)
				(type default)
			)
			(layer "B.Fab")
		)
		(pad "1" smd rect
			(at 0.889 0 270)
			(size 1.016 1.27)
			(layers "B.Cu" "B.Mask" "B.Paste")
			(net "PVCCIN_CPU0")
		)
		(pad "2" smd rect
			(at -0.889 0 270)
			(size 1.016 1.27)
			(layers "B.Cu" "B.Mask" "B.Paste")
			(net "GND")
		)
	)
	(footprint ""
		(layer "B.Cu")
		(at 366.037368 -262.348726 180)
		(property "Reference" "C1396"
			(at 0 0 0)
			(layer "B.SilkS")
			(hide yes)
			(effects
				(font
					(size 1.27 1.27)
				)
				(justify mirror)
			)
		)
		(property "Value" ""
			(at 0 0 0)
			(layer "B.Fab")
			(effects
				(font
					(size 1.27 1.27)
				)
				(justify mirror)
			)
		)
		(duplicate_pad_numbers_are_jumpers no)
		(fp_line
			(start 1.524 0.762)
			(end 1.524 -0.762)
			(stroke
				(width 0.1524)
				(type default)
			)
			(layer "B.SilkS")
		)
		(fp_line
			(start 1.524 -0.762)
			(end -1.524 -0.762)
			(stroke
				(width 0.1524)
				(type default)
			)
			(layer "B.SilkS")
		)
		(fp_line
			(start -1.524 0.762)
			(end 1.524 0.762)
			(stroke
				(width 0.1524)
				(type default)
			)
			(layer "B.SilkS")
		)
		(fp_line
			(start -1.524 -0.762)
			(end -1.524 0.762)
			(stroke
				(width 0.1524)
				(type default)
			)
			(layer "B.SilkS")
		)
		(fp_line
			(start 1.1049 0.724916)
			(end -1.1049 0.724916)
			(stroke
				(width 0.1)
				(type default)
			)
			(layer "B.Fab")
		)
		(fp_line
			(start 1.1049 -0.724916)
			(end 1.1049 0.724916)
			(stroke
				(width 0.1)
				(type default)
			)
			(layer "B.Fab")
		)
		(fp_line
			(start -1.1049 0.724916)
			(end -1.1049 -0.724916)
			(stroke
				(width 0.1)
				(type default)
			)
			(layer "B.Fab")
		)
		(fp_line
			(start -1.1049 -0.724916)
			(end 1.1049 -0.724916)
			(stroke
				(width 0.1)
				(type default)
			)
			(layer "B.Fab")
		)
		(pad "1" smd rect
			(at 0.889 0 180)
			(size 1.016 1.27)
			(layers "B.Cu" "B.Mask" "B.Paste")
			(net "PVPP_HBM_CPU0")
		)
		(pad "2" smd rect
			(at -0.889 0 180)
			(size 1.016 1.27)
			(layers "B.Cu" "B.Mask" "B.Paste")
			(net "GND")
		)
	)
)
